(kicad_pcb
	(version 20260206)
	(generator "pcbnew")
	(generator_version "10.0")
	(general
		(thickness 1.6)
		(legacy_teardrops no)
	)
	(paper "A4")
	(title_block
		(title "01162023_DA0F0TEBIF0_F0T_Expander_BD_F_brd_V02_OCP.brd")
		(comment 1 "Grand Teton / footprints 2679-2682 of 9728")
	)
	(layers
		(0 "F.Cu" signal "TOP")
		(4 "In1.Cu" signal "GND")
		(6 "In2.Cu" signal "VCC")
		(8 "In3.Cu" signal "VCC1")
		(10 "In4.Cu" signal "GND1")
		(12 "In5.Cu" signal "IN1")
		(14 "In6.Cu" signal "GND2")
		(16 "In7.Cu" signal "IN2")
		(18 "In8.Cu" signal "GND3")
		(20 "In9.Cu" signal "IN3")
		(22 "In10.Cu" signal "GND4")
		(24 "In11.Cu" signal "IN4")
		(26 "In12.Cu" signal "GND5")
		(28 "In13.Cu" signal "IN5")
		(30 "In14.Cu" signal "GND6")
		(32 "In15.Cu" signal "IN6")
		(34 "In16.Cu" signal "GND7")
		(2 "B.Cu" signal "BOTTOM")
		(9 "F.Adhes" user "F.Adhesive")
		(11 "B.Adhes" user "B.Adhesive")
		(13 "F.Paste" user "Package Geometry/Pastemask Top")
		(15 "B.Paste" user "Package Geometry/Pastemask Bottom")
		(5 "F.SilkS" user "Ref Des/Silkscreen Top")
		(7 "B.SilkS" user "Ref Des/Silkscreen Bottom")
		(1 "F.Mask" user "Board Geometry/Soldermask Top")
		(3 "B.Mask" user "Board Geometry/Soldermask Bottom")
		(17 "Dwgs.User" user "User.Drawings")
		(19 "Cmts.User" user "User.Comments")
		(21 "Eco1.User" user "User.Eco1")
		(23 "Eco2.User" user "User.Eco2")
		(25 "Edge.Cuts" user "Board Geometry/Outline")
		(27 "Margin" user)
		(31 "F.CrtYd" user "Package Geometry/Place Bound Top")
		(29 "B.CrtYd" user "Package Geometry/Place Bound Bottom")
		(35 "F.Fab" user "Ref Des/Assembly Top")
		(33 "B.Fab" user "Ref Des/Assembly Bottom")
	)
	(footprint ""
		(layer "F.Cu")
		(at 384.60553 -238.561118 90)
		(property "Reference" "U70"
			(at -6.050788 4.82727 0)
			(unlocked yes)
			(layer "F.SilkS")
			(effects
				(font
					(size 0.7874 0.5842)
					(thickness 0.1524)
				)
				(justify left)
			)
		)
		(property "Value" ""
			(at 0 0 90)
			(layer "F.Fab")
			(effects
				(font
					(size 1.27 1.27)
				)
			)
		)
		(duplicate_pad_numbers_are_jumpers no)
		(fp_line
			(start 5.050028 -5.050028)
			(end 4.0386 -5.050028)
			(stroke
				(width 0.1524)
				(type default)
			)
			(layer "F.SilkS")
		)
		(fp_line
			(start -4.0386 -5.050028)
			(end -5.050028 -5.050028)
			(stroke
				(width 0.1524)
				(type default)
			)
			(layer "F.SilkS")
		)
		(fp_line
			(start -5.050028 -5.050028)
			(end -5.050028 -4.0386)
			(stroke
				(width 0.1524)
				(type default)
			)
			(layer "F.SilkS")
		)
		(fp_line
			(start 5.050028 -4.0386)
			(end 5.050028 -5.050028)
			(stroke
				(width 0.1524)
				(type default)
			)
			(layer "F.SilkS")
		)
		(fp_line
			(start -5.050028 4.0386)
			(end -5.050028 5.050028)
			(stroke
				(width 0.1524)
				(type default)
			)
			(layer "F.SilkS")
		)
		(fp_line
			(start 5.050028 5.050028)
			(end 5.050028 4.0386)
			(stroke
				(width 0.1524)
				(type default)
			)
			(layer "F.SilkS")
		)
		(fp_line
			(start 4.0386 5.050028)
			(end 5.050028 5.050028)
			(stroke
				(width 0.1524)
				(type default)
			)
			(layer "F.SilkS")
		)
		(fp_line
			(start -5.050028 5.050028)
			(end -4.0386 5.050028)
			(stroke
				(width 0.1524)
				(type default)
			)
			(layer "F.SilkS")
		)
		(fp_poly
			(pts
				(xy -5.535676 -5.262372) (xy -6.551676 -5.262372) (xy -6.043676 -4.246372)
			)
			(stroke
				(width 0)
				(type default)
			)
			(fill yes)
			(layer "F.SilkS")
		)
		(fp_line
			(start 5.050028 -5.050028)
			(end -5.050028 -5.050028)
			(stroke
				(width 0.1)
				(type default)
			)
			(layer "F.Fab")
		)
		(fp_line
			(start -5.050028 -5.050028)
			(end -5.050028 5.050028)
			(stroke
				(width 0.1)
				(type default)
			)
			(layer "F.Fab")
		)
		(fp_line
			(start 5.050028 5.050028)
			(end 5.050028 -5.050028)
			(stroke
				(width 0.1)
				(type default)
			)
			(layer "F.Fab")
		)
		(fp_line
			(start -5.050028 5.050028)
			(end 5.050028 5.050028)
			(stroke
				(width 0.1)
				(type default)
			)
			(layer "F.Fab")
		)
		(fp_poly
			(pts
				(xy -7.62 -4.258056) (xy -7.62 -3.242056) (xy -6.604 -3.750056)
			)
			(stroke
				(width 0)
				(type default)
			)
			(fill yes)
			(layer "F.Fab")
		)
		(pad "1" smd rect
			(at -5.724906 -3.750056)
			(size 0.2794 1.3716)
			(layers "F.Cu" "F.Mask" "F.Paste")
			(net "GND")
		)
		(pad "2" smd rect
			(at -5.724906 -3.24993)
			(size 0.2794 1.3716)
			(layers "F.Cu" "F.Mask" "F.Paste")
			(net "OSC_SDB_IN")
		)
		(pad "3" smd rect
			(at -5.724906 -2.750058)
			(size 0.2794 1.3716)
			(layers "F.Cu" "F.Mask" "F.Paste")
			(net "OSC_SDB_OUT")
		)
		(pad "4" smd rect
			(at -5.724906 -2.249932)
			(size 0.2794 1.3716)
			(layers "F.Cu" "F.Mask" "F.Paste")
			(net "P3V3_SDB_VPHY")
		)
		(pad "5" smd rect
			(at -5.724906 -1.75006)
			(size 0.2794 1.3716)
			(layers "F.Cu" "F.Mask" "F.Paste")
			(net "GND")
		)
		(pad "6" smd rect
			(at -5.724906 -1.249934)
			(size 0.2794 1.3716)
			(layers "F.Cu" "F.Mask" "F.Paste")
			(net "FT4232_SDB_REF")
		)
		(pad "7" smd rect
			(at -5.724906 -0.750062)
			(size 0.2794 1.3716)
			(layers "F.Cu" "F.Mask" "F.Paste")
			(net "USB2_FT4232_SDB_DN")
		)
		(pad "8" smd rect
			(at -5.724906 -0.249936)
			(size 0.2794 1.3716)
			(layers "F.Cu" "F.Mask" "F.Paste")
			(net "USB2_FT4232_SDB_DP")
		)
		(pad "9" smd rect
			(at -5.724906 0.249936)
			(size 0.2794 1.3716)
			(layers "F.Cu" "F.Mask" "F.Paste")
			(net "P3V3_SDB_VPLL")
		)
		(pad "10" smd rect
			(at -5.724906 0.750062)
			(size 0.2794 1.3716)
			(layers "F.Cu" "F.Mask" "F.Paste")
			(net "GND")
		)
		(pad "11" smd rect
			(at -5.724906 1.249934)
			(size 0.2794 1.3716)
			(layers "F.Cu" "F.Mask" "F.Paste")
			(net "GND")
		)
		(pad "12" smd rect
			(at -5.724906 1.75006)
			(size 0.2794 1.3716)
			(layers "F.Cu" "F.Mask" "F.Paste")
			(net "P1V8_SDB_VCORE")
		)
		(pad "13" smd rect
			(at -5.724906 2.249932)
			(size 0.2794 1.3716)
			(layers "F.Cu" "F.Mask" "F.Paste")
			(net "GND")
		)
		(pad "14" smd rect
			(at -5.724906 2.750058)
			(size 0.2794 1.3716)
			(layers "F.Cu" "F.Mask" "F.Paste")
			(net "RST_FT4232_SDB_R_N")
		)
		(pad "15" smd rect
			(at -5.724906 3.24993)
			(size 0.2794 1.3716)
			(layers "F.Cu" "F.Mask" "F.Paste")
			(net "GND")
		)
		(pad "16" smd rect
			(at -5.724906 3.750056)
			(size 0.2794 1.3716)
			(layers "F.Cu" "F.Mask" "F.Paste")
			(net "UART_PEX0_SDB_RX")
		)
		(pad "17" smd rect
			(at -3.750056 5.724906 90)
			(size 0.2794 1.3716)
			(layers "F.Cu" "F.Mask" "F.Paste")
			(net "UART_PEX0_SDB_BUF_TX")
		)
		(pad "18" smd rect
			(at -3.24993 5.724906 90)
			(size 0.2794 1.3716)
			(layers "F.Cu" "F.Mask" "F.Paste")
			(net "Net_8958")
		)
		(pad "19" smd rect
			(at -2.750058 5.724906 90)
			(size 0.2794 1.3716)
			(layers "F.Cu" "F.Mask" "F.Paste")
			(net "Net_8957")
		)
		(pad "20" smd rect
			(at -2.249932 5.724906 90)
			(size 0.2794 1.3716)
			(layers "F.Cu" "F.Mask" "F.Paste")
			(net "P3V3_AUX")
		)
		(pad "21" smd rect
			(at -1.75006 5.724906 90)
			(size 0.2794 1.3716)
			(layers "F.Cu" "F.Mask" "F.Paste")
			(net "Net_8956")
		)
		(pad "22" smd rect
			(at -1.249934 5.724906 90)
			(size 0.2794 1.3716)
			(layers "F.Cu" "F.Mask" "F.Paste")
			(net "Net_8955")
		)
		(pad "23" smd rect
			(at -0.750062 5.724906 90)
			(size 0.2794 1.3716)
			(layers "F.Cu" "F.Mask" "F.Paste")
			(net "Net_8954")
		)
		(pad "24" smd rect
			(at -0.249936 5.724906 90)
			(size 0.2794 1.3716)
			(layers "F.Cu" "F.Mask" "F.Paste")
			(net "Net_8953")
		)
		(pad "25" smd rect
			(at 0.249936 5.724906 90)
			(size 0.2794 1.3716)
			(layers "F.Cu" "F.Mask" "F.Paste")
			(net "GND")
		)
		(pad "26" smd rect
			(at 0.750062 5.724906 90)
			(size 0.2794 1.3716)
			(layers "F.Cu" "F.Mask" "F.Paste")
			(net "UART_PEX1_SDB_RX")
		)
		(pad "27" smd rect
			(at 1.249934 5.724906 90)
			(size 0.2794 1.3716)
			(layers "F.Cu" "F.Mask" "F.Paste")
			(net "UART_PEX1_SDB_BUF_TX")
		)
		(pad "28" smd rect
			(at 1.75006 5.724906 90)
			(size 0.2794 1.3716)
			(layers "F.Cu" "F.Mask" "F.Paste")
			(net "Net_8952")
		)
		(pad "29" smd rect
			(at 2.249932 5.724906 90)
			(size 0.2794 1.3716)
			(layers "F.Cu" "F.Mask" "F.Paste")
			(net "Net_8951")
		)
		(pad "30" smd rect
			(at 2.750058 5.724906 90)
			(size 0.2794 1.3716)
			(layers "F.Cu" "F.Mask" "F.Paste")
			(net "Net_8950")
		)
		(pad "31" smd rect
			(at 3.24993 5.724906 90)
			(size 0.2794 1.3716)
			(layers "F.Cu" "F.Mask" "F.Paste")
			(net "P3V3_AUX")
		)
		(pad "32" smd rect
			(at 3.750056 5.724906 90)
			(size 0.2794 1.3716)
			(layers "F.Cu" "F.Mask" "F.Paste")
			(net "Net_8949")
		)
		(pad "33" smd rect
			(at 5.724906 3.750056)
			(size 0.2794 1.3716)
			(layers "F.Cu" "F.Mask" "F.Paste")
			(net "Net_8948")
		)
		(pad "34" smd rect
			(at 5.724906 3.24993)
			(size 0.2794 1.3716)
			(layers "F.Cu" "F.Mask" "F.Paste")
			(net "Net_8947")
		)
		(pad "35" smd rect
			(at 5.724906 2.750058)
			(size 0.2794 1.3716)
			(layers "F.Cu" "F.Mask" "F.Paste")
			(net "GND")
		)
		(pad "36" smd rect
			(at 5.724906 2.249932)
			(size 0.2794 1.3716)
			(layers "F.Cu" "F.Mask" "F.Paste")
			(net "Net_8933")
		)
		(pad "37" smd rect
			(at 5.724906 1.75006)
			(size 0.2794 1.3716)
			(layers "F.Cu" "F.Mask" "F.Paste")
			(net "P1V8_SDB_VCORE")
		)
		(pad "38" smd rect
			(at 5.724906 1.249934)
			(size 0.2794 1.3716)
			(layers "F.Cu" "F.Mask" "F.Paste")
			(net "UART_PEX2_SDB_RX")
		)
		(pad "39" smd rect
			(at 5.724906 0.750062)
			(size 0.2794 1.3716)
			(layers "F.Cu" "F.Mask" "F.Paste")
			(net "UART_PEX2_SDB_BUF_TX")
		)
		(pad "40" smd rect
			(at 5.724906 0.249936)
			(size 0.2794 1.3716)
			(layers "F.Cu" "F.Mask" "F.Paste")
			(net "Net_8946")
		)
		(pad "41" smd rect
			(at 5.724906 -0.249936)
			(size 0.2794 1.3716)
			(layers "F.Cu" "F.Mask" "F.Paste")
			(net "Net_8945")
		)
		(pad "42" smd rect
			(at 5.724906 -0.750062)
			(size 0.2794 1.3716)
			(layers "F.Cu" "F.Mask" "F.Paste")
			(net "P3V3_AUX")
		)
		(pad "43" smd rect
			(at 5.724906 -1.249934)
			(size 0.2794 1.3716)
			(layers "F.Cu" "F.Mask" "F.Paste")
			(net "Net_8944")
		)
		(pad "44" smd rect
			(at 5.724906 -1.75006)
			(size 0.2794 1.3716)
			(layers "F.Cu" "F.Mask" "F.Paste")
			(net "Net_8943")
		)
		(pad "45" smd rect
			(at 5.724906 -2.249932)
			(size 0.2794 1.3716)
			(layers "F.Cu" "F.Mask" "F.Paste")
			(net "Net_8942")
		)
		(pad "46" smd rect
			(at 5.724906 -2.750058)
			(size 0.2794 1.3716)
			(layers "F.Cu" "F.Mask" "F.Paste")
			(net "Net_8941")
		)
		(pad "47" smd rect
			(at 5.724906 -3.24993)
			(size 0.2794 1.3716)
			(layers "F.Cu" "F.Mask" "F.Paste")
			(net "GND")
		)
		(pad "48" smd rect
			(at 5.724906 -3.750056)
			(size 0.2794 1.3716)
			(layers "F.Cu" "F.Mask" "F.Paste")
			(net "UART_PEX3_SDB_RX")
		)
		(pad "49" smd rect
			(at 3.750056 -5.724906 90)
			(size 0.2794 1.3716)
			(layers "F.Cu" "F.Mask" "F.Paste")
			(net "P1V8_SDB_VCORE")
		)
		(pad "50" smd rect
			(at 3.24993 -5.724906 90)
			(size 0.2794 1.3716)
			(layers "F.Cu" "F.Mask" "F.Paste")
			(net "P3V3_AUX")
		)
		(pad "51" smd rect
			(at 2.750058 -5.724906 90)
			(size 0.2794 1.3716)
			(layers "F.Cu" "F.Mask" "F.Paste")
			(net "GND")
		)
		(pad "52" smd rect
			(at 2.249932 -5.724906 90)
			(size 0.2794 1.3716)
			(layers "F.Cu" "F.Mask" "F.Paste")
			(net "UART_PEX3_SDB_BUF_TX")
		)
		(pad "53" smd rect
			(at 1.75006 -5.724906 90)
			(size 0.2794 1.3716)
			(layers "F.Cu" "F.Mask" "F.Paste")
			(net "Net_8940")
		)
		(pad "54" smd rect
			(at 1.249934 -5.724906 90)
			(size 0.2794 1.3716)
			(layers "F.Cu" "F.Mask" "F.Paste")
			(net "Net_8939")
		)
		(pad "55" smd rect
			(at 0.750062 -5.724906 90)
			(size 0.2794 1.3716)
			(layers "F.Cu" "F.Mask" "F.Paste")
			(net "Net_8938")
		)
		(pad "56" smd rect
			(at 0.249936 -5.724906 90)
			(size 0.2794 1.3716)
			(layers "F.Cu" "F.Mask" "F.Paste")
			(net "P3V3_AUX")
		)
		(pad "57" smd rect
			(at -0.249936 -5.724906 90)
			(size 0.2794 1.3716)
			(layers "F.Cu" "F.Mask" "F.Paste")
			(net "Net_8937")
		)
		(pad "58" smd rect
			(at -0.750062 -5.724906 90)
			(size 0.2794 1.3716)
			(layers "F.Cu" "F.Mask" "F.Paste")
			(net "Net_8936")
		)
		(pad "59" smd rect
			(at -1.249934 -5.724906 90)
			(size 0.2794 1.3716)
			(layers "F.Cu" "F.Mask" "F.Paste")
			(net "Net_8935")
		)
		(pad "60" smd rect
			(at -1.75006 -5.724906 90)
			(size 0.2794 1.3716)
			(layers "F.Cu" "F.Mask" "F.Paste")
			(net "Net_8934")
		)
		(pad "61" smd rect
			(at -2.249932 -5.724906 90)
			(size 0.2794 1.3716)
			(layers "F.Cu" "F.Mask" "F.Paste")
			(net "FT4232_SDB_EEPROM_SDA")
		)
		(pad "62" smd rect
			(at -2.750058 -5.724906 90)
			(size 0.2794 1.3716)
			(layers "F.Cu" "F.Mask" "F.Paste")
			(net "FT4232_SDB_EEPROM_SCL")
		)
		(pad "63" smd rect
			(at -3.24993 -5.724906 90)
			(size 0.2794 1.3716)
			(layers "F.Cu" "F.Mask" "F.Paste")
			(net "FT4232_SDB_EEPROM_CS")
		)
		(pad "64" smd rect
			(at -3.750056 -5.724906 90)
			(size 0.2794 1.3716)
			(layers "F.Cu" "F.Mask" "F.Paste")
			(net "P1V8_SDB_VCORE")
		)
	)
	(footprint ""
		(layer "F.Cu")
		(at 348.04731 -253.178564 180)
		(property "Reference" "PC127"
			(at 0 0 180)
			(layer "F.SilkS")
			(hide yes)
			(effects
				(font
					(size 1.27 1.27)
				)
			)
		)
		(property "Value" ""
			(at 0 0 180)
			(layer "F.Fab")
			(effects
				(font
					(size 1.27 1.27)
				)
			)
		)
		(duplicate_pad_numbers_are_jumpers no)
		(fp_line
			(start 1.524 0.762)
			(end -1.524 0.762)
			(stroke
				(width 0.1524)
				(type default)
			)
			(layer "F.SilkS")
		)
		(fp_line
			(start 1.524 -0.762)
			(end 1.524 0.762)
			(stroke
				(width 0.1524)
				(type default)
			)
			(layer "F.SilkS")
		)
		(fp_line
			(start -1.524 0.762)
			(end -1.524 -0.762)
			(stroke
				(width 0.1524)
				(type default)
			)
			(layer "F.SilkS")
		)
		(fp_line
			(start -1.524 -0.762)
			(end 1.524 -0.762)
			(stroke
				(width 0.1524)
				(type default)
			)
			(layer "F.SilkS")
		)
		(fp_line
			(start 1.1049 0.724916)
			(end 1.1049 -0.724916)
			(stroke
				(width 0.1)
				(type default)
			)
			(layer "F.Fab")
		)
		(fp_line
			(start 1.1049 -0.724916)
			(end -1.1049 -0.724916)
			(stroke
				(width 0.1)
				(type default)
			)
			(layer "F.Fab")
		)
		(fp_line
			(start -1.1049 0.724916)
			(end 1.1049 0.724916)
			(stroke
				(width 0.1)
				(type default)
			)
			(layer "F.Fab")
		)
		(fp_line
			(start -1.1049 -0.724916)
			(end -1.1049 0.724916)
			(stroke
				(width 0.1)
				(type default)
			)
			(layer "F.Fab")
		)
		(pad "1" smd rect
			(at -0.889 0)
			(size 1.016 1.27)
			(layers "F.Cu" "F.Mask" "F.Paste")
			(net "P0V8_PEX2_VREF")
		)
		(pad "2" smd rect
			(at 0.889 0)
			(size 1.016 1.27)
			(layers "F.Cu" "F.Mask" "F.Paste")
			(net "GND")
		)
	)
	(footprint ""
		(layer "F.Cu")
		(at 68.479162 -356.244906 90)
		(property "Reference" "C136"
			(at 0 0 90)
			(layer "F.SilkS")
			(hide yes)
			(effects
				(font
					(size 1.27 1.27)
				)
			)
		)
		(property "Value" ""
			(at 0 0 90)
			(layer "F.Fab")
			(effects
				(font
					(size 1.27 1.27)
				)
			)
		)
		(duplicate_pad_numbers_are_jumpers no)
		(fp_line
			(start 0.299974 -0.150114)
			(end 0.299974 0.150114)
			(stroke
				(width 0.1)
				(type default)
			)
			(layer "F.Fab")
		)
		(fp_line
			(start -0.299974 -0.150114)
			(end 0.299974 -0.150114)
			(stroke
				(width 0.1)
				(type default)
			)
			(layer "F.Fab")
		)
		(fp_line
			(start 0.299974 0.150114)
			(end -0.299974 0.150114)
			(stroke
				(width 0.1)
				(type default)
			)
			(layer "F.Fab")
		)
		(fp_line
			(start -0.299974 0.150114)
			(end -0.299974 -0.150114)
			(stroke
				(width 0.1)
				(type default)
			)
			(layer "F.Fab")
		)
		(pad "1" smd rect
			(at -0.2667 0 90)
			(size 0.3048 0.381)
			(layers "F.Cu" "F.Mask" "F.Paste")
			(net "P5E_PEX0_STN6_TX_DN<108>")
		)
		(pad "2" smd rect
			(at 0.2667 0 90)
			(size 0.3048 0.381)
			(layers "F.Cu" "F.Mask" "F.Paste")
			(net "P5E_PEX0_STN6_TX_C_DN<108>")
		)
	)
	(footprint ""
		(layer "F.Cu")
		(at 1.978406 -26.670254 180)
		(property "Reference" "C2712"
			(at 0 0 180)
			(layer "F.SilkS")
			(hide yes)
			(effects
				(font
					(size 1.27 1.27)
				)
			)
		)
		(property "Value" ""
			(at 0 0 180)
			(layer "F.Fab")
			(effects
				(font
					(size 1.27 1.27)
				)
			)
		)
		(duplicate_pad_numbers_are_jumpers no)
		(fp_line
			(start 0.7874 0.4064)
			(end -0.7874 0.4064)
			(stroke
				(width 0.1524)
				(type default)
			)
			(layer "F.SilkS")
		)
		(fp_line
			(start 0.7874 -0.4064)
			(end 0.7874 0.4064)
			(stroke
				(width 0.1524)
				(type default)
			)
			(layer "F.SilkS")
		)
		(fp_line
			(start -0.7874 0.4064)
			(end -0.7874 -0.4064)
			(stroke
				(width 0.1524)
				(type default)
			)
			(layer "F.SilkS")
		)
		(fp_line
			(start -0.7874 -0.4064)
			(end 0.7874 -0.4064)
			(stroke
				(width 0.1524)
				(type default)
			)
			(layer "F.SilkS")
		)
		(fp_line
			(start 0.67945 0.3048)
			(end 0.120396 0.3048)
			(stroke
				(width 0.1)
				(type default)
			)
			(layer "F.Fab")
		)
		(fp_line
			(start 0.67945 -0.3048)
			(end 0.67945 0.3048)
			(stroke
				(width 0.1)
				(type default)
			)
			(layer "F.Fab")
		)
		(fp_line
			(start 0.12065 -0.2794)
			(end 0.12065 -0.3048)
			(stroke
				(width 0.1)
				(type default)
			)
			(layer "F.Fab")
		)
		(fp_line
			(start 0.12065 -0.3048)
			(end 0.67945 -0.3048)
			(stroke
				(width 0.1)
				(type default)
			)
			(layer "F.Fab")
		)
		(fp_line
			(start 0.120396 0.3048)
			(end 0.120396 0.2794)
			(stroke
				(width 0.1)
				(type default)
			)
			(layer "F.Fab")
		)
		(fp_line
			(start 0.120396 0.2794)
			(end -0.12065 0.2794)
			(stroke
				(width 0.1)
				(type default)
			)
			(layer "F.Fab")
		)
		(fp_line
			(start -0.12065 0.3048)
			(end -0.67945 0.3048)
			(stroke
				(width 0.1)
				(type default)
			)
			(layer "F.Fab")
		)
		(fp_line
			(start -0.12065 0.2794)
			(end -0.12065 0.3048)
			(stroke
				(width 0.1)
				(type default)
			)
			(layer "F.Fab")
		)
		(fp_line
			(start -0.12065 -0.2794)
			(end 0.12065 -0.2794)
			(stroke
				(width 0.1)
				(type default)
			)
			(layer "F.Fab")
		)
		(fp_line
			(start -0.12065 -0.305054)
			(end -0.12065 -0.2794)
			(stroke
				(width 0.1)
				(type default)
			)
			(layer "F.Fab")
		)
		(fp_line
			(start -0.67945 0.3048)
			(end -0.67945 -0.305054)
			(stroke
				(width 0.1)
				(type default)
			)
			(layer "F.Fab")
		)
		(fp_line
			(start -0.67945 -0.305054)
			(end -0.12065 -0.305054)
			(stroke
				(width 0.1)
				(type default)
			)
			(layer "F.Fab")
		)
		(pad "1" smd circle
			(at -0.40005 0 180)
			(size 0 0)
			(layers "F.Cu" "F.Mask" "F.Paste")
			(net "GND")
		)
		(pad "2" smd circle
			(at 0.40005 0 180)
			(size 0 0)
			(layers "F.Cu" "F.Mask" "F.Paste")
			(net "P3V3_SSD0")
		)
	)
)
